# BASEBOARD_FAB2 (Tioga Pass) — schematic netlist excerpt (pin names and nets, part order shuffled) for the footprints in the layout excerpt that follows; sources: Cadence DE-HDL packaged netlist, KiCad conversion of Wiwynn_Tioga_Pass_MB.brd

R25W13  120R2F-GP  1%  pkg RCL_GP  page 151 : \1\ = GND ; \2\ = BMC_M_A1
C5P24  CAP  47UF 4V 20% X6S  pkg 0805  page 42 : A = PVCCIN_CPU0 ; B = GND
R6U4  RES  0.0 5% CHIP  pkg 0402  page 221 : A = P3V3 ; B = VR_PVTT_ABC_BIAS

(kicad_pcb
	(version 20260206)
	(generator "pcbnew")
	(generator_version "10.0")
	(general
		(thickness 1.6)
		(legacy_teardrops no)
	)
	(paper "A4")
	(title_block
		(title "Wiwynn_Tioga_Pass_MB.brd")
		(comment 1 "Tioga Pass / footprints 3664-3666 of 4770")
	)
	(layers
		(0 "F.Cu" signal "TOP")
		(4 "In1.Cu" signal "L2GND")
		(6 "In2.Cu" signal "L3")
		(8 "In3.Cu" signal "L4GND")
		(10 "In4.Cu" signal "L5")
		(12 "In5.Cu" signal "L6GND")
		(14 "In6.Cu" signal "L7VCC")
		(16 "In7.Cu" signal "L8VCC")
		(18 "In8.Cu" signal "L9GND")
		(20 "In9.Cu" signal "L10")
		(22 "In10.Cu" signal "L11GND")
		(24 "In11.Cu" signal "L12")
		(26 "In12.Cu" signal "L13GND")
		(2 "B.Cu" signal "BOTTOM")
		(9 "F.Adhes" user "F.Adhesive")
		(11 "B.Adhes" user "B.Adhesive")
		(13 "F.Paste" user "Package Geometry/Pastemask Top")
		(15 "B.Paste" user "Package Geometry/Pastemask Bottom")
		(5 "F.SilkS" user "Ref Des/Silkscreen Top")
		(7 "B.SilkS" user "Ref Des/Silkscreen Bottom")
		(1 "F.Mask" user "Board Geometry/Soldermask Top")
		(3 "B.Mask" user "Board Geometry/Soldermask Bottom")
		(17 "Dwgs.User" user "User.Drawings")
		(19 "Cmts.User" user "User.Comments")
		(21 "Eco1.User" user "User.Eco1")
		(23 "Eco2.User" user "User.Eco2")
		(25 "Edge.Cuts" user "Board Geometry/Outline")
		(27 "Margin" user)
		(31 "F.CrtYd" user "Package Geometry/Place Bound Top")
		(29 "B.CrtYd" user "Package Geometry/Place Bound Bottom")
		(35 "F.Fab" user "Ref Des/Assembly Top")
		(33 "B.Fab" user "Ref Des/Assembly Bottom")
	)
	(footprint ""
		(layer "B.Cu")
		(at 183.625998 -5.321808)
		(property "Reference" "R6U4"
			(at 0 0 0)
			(layer "B.SilkS")
			(hide yes)
			(effects
				(font
					(size 1.27 1.27)
				)
				(justify mirror)
			)
		)
		(property "Value" ""
			(at 0 0 0)
			(layer "B.Fab")
			(effects
				(font
					(size 1.27 1.27)
				)
				(justify mirror)
			)
		)
		(duplicate_pad_numbers_are_jumpers no)
		(fp_rect
			(start -0.2794 0.9906)
			(end 0.2794 -0.1016)
			(stroke
				(width 0)
				(type default)
			)
			(fill no)
			(layer "B.CrtYd")
		)
		(fp_line
			(start -0.2794 -0.1016)
			(end 0.2794 -0.1016)
			(stroke
				(width 0.1)
				(type default)
			)
			(layer "B.Fab")
		)
		(fp_line
			(start -0.2794 0.9906)
			(end -0.2794 -0.1016)
			(stroke
				(width 0.1)
				(type default)
			)
			(layer "B.Fab")
		)
		(fp_line
			(start 0.2794 -0.1016)
			(end 0.2794 0.9906)
			(stroke
				(width 0.1)
				(type default)
			)
			(layer "B.Fab")
		)
		(fp_line
			(start 0.2794 0.9906)
			(end -0.2794 0.9906)
			(stroke
				(width 0.1)
				(type default)
			)
			(layer "B.Fab")
		)
		(pad "1" smd rect
			(at 0 0 180)
			(size 0.508 0.508)
			(layers "B.Cu" "B.Mask" "B.Paste")
			(net "P3V3")
		)
		(pad "2" smd rect
			(at 0 0.889 180)
			(size 0.508 0.508)
			(layers "B.Cu" "B.Mask" "B.Paste")
			(net "VR_PVTT_ABC_BIAS")
		)
		(zone
			(layer "B.Cu")
			(hatch none 0.5)
			(connect_pads
				(clearance 0)
			)
			(min_thickness 0.25)
			(keepout
				(tracks allowed)
				(vias not_allowed)
				(pads allowed)
				(copperpour not_allowed)
				(footprints allowed)
			)
			(placement
				(enabled no)
				(sheetname "")
			)
			(fill
				(thermal_gap 0.5)
				(thermal_bridge_width 0.5)
				(island_removal_mode 0)
			)
			(polygon
				(pts
					(xy 183.371998 -4.686808) (xy 183.879998 -4.686808) (xy 183.879998 -5.067808) (xy 183.371998 -5.067808)
				)
			)
		)
	)
	(footprint ""
		(layer "B.Cu")
		(at 264.035286 -77.82814)
		(property "Reference" "C5P24"
			(at 0 0 0)
			(layer "B.SilkS")
			(hide yes)
			(effects
				(font
					(size 1.27 1.27)
				)
				(justify mirror)
			)
		)
		(property "Value" ""
			(at 0 0 0)
			(layer "B.Fab")
			(effects
				(font
					(size 1.27 1.27)
				)
				(justify mirror)
			)
		)
		(duplicate_pad_numbers_are_jumpers no)
		(fp_poly
			(pts
				(xy 0.7239 -0.2159) (xy -0.7239 -0.2159) (xy -0.7239 1.9939) (xy 0.7239 1.9939)
			)
			(stroke
				(width 0)
				(type default)
			)
			(fill no)
			(layer "B.CrtYd")
		)
		(fp_line
			(start -0.7239 -0.2159)
			(end 0.7239 -0.2159)
			(stroke
				(width 0.1)
				(type default)
			)
			(layer "B.Fab")
		)
		(fp_line
			(start -0.7239 1.9939)
			(end -0.7239 -0.2159)
			(stroke
				(width 0.1)
				(type default)
			)
			(layer "B.Fab")
		)
		(fp_line
			(start 0.7239 -0.2159)
			(end 0.7239 1.9939)
			(stroke
				(width 0.1)
				(type default)
			)
			(layer "B.Fab")
		)
		(fp_line
			(start 0.7239 1.9939)
			(end -0.7239 1.9939)
			(stroke
				(width 0.1)
				(type default)
			)
			(layer "B.Fab")
		)
		(pad "1" smd rect
			(at 0 0 180)
			(size 1.27 1.016)
			(layers "B.Cu" "B.Mask" "B.Paste")
			(net "PVCCIN_CPU0")
		)
		(pad "2" smd rect
			(at 0 1.778 180)
			(size 1.27 1.016)
			(layers "B.Cu" "B.Mask" "B.Paste")
			(net "GND")
		)
		(zone
			(layer "B.Cu")
			(hatch none 0.5)
			(connect_pads
				(clearance 0)
			)
			(min_thickness 0.25)
			(keepout
				(tracks not_allowed)
				(vias allowed)
				(pads allowed)
				(copperpour not_allowed)
				(footprints allowed)
			)
			(placement
				(enabled no)
				(sheetname "")
			)
			(fill
				(thermal_gap 0.5)
				(thermal_bridge_width 0.5)
				(island_removal_mode 0)
			)
			(polygon
				(pts
					(xy 264.670286 -77.32014) (xy 263.400286 -77.32014) (xy 263.400286 -76.55814) (xy 264.670286 -76.55814)
				)
			)
		)
	)
	(footprint ""
		(layer "B.Cu")
		(at 437.690006 -41.648126 180)
		(property "Reference" "R25W13"
			(at 0 0 0)
			(layer "B.SilkS")
			(hide yes)
			(effects
				(font
					(size 1.27 1.27)
				)
				(justify mirror)
			)
		)
		(property "Value" "*"
			(at -0.064008 -4.108196 180)
			(unlocked yes)
			(layer "B.Fab")
			(hide yes)
			(effects
				(font
					(size 1.27 1.016)
					(thickness 0.1524)
				)
				(justify mirror)
			)
		)
		(property "Device Type" "120R2F-GP_RCL_GP-120R2F-GP,64.A"
			(at -0.064008 -5.632196 180)
			(unlocked yes)
			(layer "B.Fab")
			(hide yes)
			(effects
				(font
					(size 1.27 1.016)
					(thickness 0.1524)
				)
				(justify mirror)
			)
		)
		(duplicate_pad_numbers_are_jumpers no)
		(fp_line
			(start 0.508 -0.9398)
			(end 0.508 0.9398)
			(stroke
				(width 0.1524)
				(type default)
			)
			(layer "B.SilkS")
		)
		(fp_line
			(start -0.508 -0.9398)
			(end 0.508 -0.9398)
			(stroke
				(width 0.1524)
				(type default)
			)
			(layer "B.SilkS")
		)
		(fp_rect
			(start 0.508 0.9398)
			(end -0.508 -0.9398)
			(stroke
				(width 0)
				(type default)
			)
			(fill no)
			(layer "B.CrtYd")
		)
		(fp_rect
			(start 0.508 0.9398)
			(end -0.508 -0.9398)
			(stroke
				(width 0)
				(type default)
			)
			(fill no)
			(layer "B.Fab")
		)
		(pad "1" smd custom
			(at 0 -0.4445)
			(size 0.1397 0.1397)
			(layers "B.Cu" "B.Mask" "B.Paste")
			(net "GND")
			(options
				(clearance outline)
				(anchor circle)
			)
			(primitives
				(gr_poly
					(pts
						(arc
							(start -0.1778 0.2794)
							(mid -0.249642 0.249642)
							(end -0.2794 0.1778)
						)
						(arc
							(start -0.2794 -0.1778)
							(mid -0.249642 -0.249642)
							(end -0.1778 -0.2794)
						)
						(arc
							(start 0.1778 -0.2794)
							(mid 0.249642 -0.249642)
							(end 0.2794 -0.1778)
						)
						(arc
							(start 0.2794 0.1778)
							(mid 0.249642 0.249642)
							(end 0.1778 0.2794)
						)
					)
					(width 0)
					(fill yes)
				)
			)
		)
		(pad "2" smd custom
			(at 0 0.4445)
			(size 0.1397 0.1397)
			(layers "B.Cu" "B.Mask" "B.Paste")
			(net "BMC_M_A1")
			(options
				(clearance outline)
				(anchor circle)
			)
			(primitives
				(gr_poly
					(pts
						(arc
							(start -0.1778 0.2794)
							(mid -0.249642 0.249642)
							(end -0.2794 0.1778)
						)
						(arc
							(start -0.2794 -0.1778)
							(mid -0.249642 -0.249642)
							(end -0.1778 -0.2794)
						)
						(arc
							(start 0.1778 -0.2794)
							(mid 0.249642 -0.249642)
							(end 0.2794 -0.1778)
						)
						(arc
							(start 0.2794 0.1778)
							(mid 0.249642 0.249642)
							(end 0.1778 0.2794)
						)
					)
					(width 0)
					(fill yes)
				)
			)
		)
	)
)
